# S9S_MB_2U (Grand Teton) — schematic netlist excerpt (pin names and nets, part order shuffled) for the footprints in the layout excerpt that follows; sources: Cadence DE-HDL packaged netlist, KiCad conversion of 03242023_DA0F0TMBIJ0_F0T_Motherboard_J_brd_V01_OCP.brd

C1018  Q_CAP  22UF 4V 20% X6S  pkg C0402  page 74 : A = PVCCIN_CPU0 ; B = GND
PC502  Q_CAP  2.2UF 10V 10% X6S  pkg C0402  page 287 : A = PVCCIN_CPU1_VDD5 ; B = GND
C678  Q_CAP_DIFFBUS  DIFF BUS_0.22UF 6.3V 20% X6S  pkg C0201  page 177 : \1\ = P5E_CPU1_PE4_TX_C_DN<15> ; \2\ = P5E_CPU1_PE4_TX_DN<15>

(kicad_pcb
	(version 20260206)
	(generator "pcbnew")
	(generator_version "10.0")
	(general
		(thickness 1.6)
		(legacy_teardrops no)
	)
	(paper "A4")
	(title_block
		(title "03242023_DA0F0TMBIJ0_F0T_Motherboard_J_brd_V01_OCP.brd")
		(comment 1 "Grand Teton / footprints 514-516 of 6105")
	)
	(layers
		(0 "F.Cu" signal "TOP")
		(4 "In1.Cu" signal "GND")
		(6 "In2.Cu" signal "IN1")
		(8 "In3.Cu" signal "GND1")
		(10 "In4.Cu" signal "IN2")
		(12 "In5.Cu" signal "GND2")
		(14 "In6.Cu" signal "IN3")
		(16 "In7.Cu" signal "GND3")
		(18 "In8.Cu" signal "VCC")
		(20 "In9.Cu" signal "VCC1")
		(22 "In10.Cu" signal "GND4")
		(24 "In11.Cu" signal "IN4")
		(26 "In12.Cu" signal "GND5")
		(28 "In13.Cu" signal "IN5")
		(30 "In14.Cu" signal "GND6")
		(32 "In15.Cu" signal "IN6")
		(34 "In16.Cu" signal "GND7")
		(2 "B.Cu" signal "BOTTOM")
		(9 "F.Adhes" user "F.Adhesive")
		(11 "B.Adhes" user "B.Adhesive")
		(13 "F.Paste" user "Package Geometry/Pastemask Top")
		(15 "B.Paste" user "Package Geometry/Pastemask Bottom")
		(5 "F.SilkS" user "Ref Des/Silkscreen Top")
		(7 "B.SilkS" user "Ref Des/Silkscreen Bottom")
		(1 "F.Mask" user "Board Geometry/Soldermask Top")
		(3 "B.Mask" user "Board Geometry/Soldermask Bottom")
		(17 "Dwgs.User" user "User.Drawings")
		(19 "Cmts.User" user "User.Comments")
		(21 "Eco1.User" user "User.Eco1")
		(23 "Eco2.User" user "User.Eco2")
		(25 "Edge.Cuts" user "Board Geometry/Outline")
		(27 "Margin" user)
		(31 "F.CrtYd" user "Package Geometry/Place Bound Top")
		(29 "B.CrtYd" user "Package Geometry/Place Bound Bottom")
		(35 "F.Fab" user "Ref Des/Assembly Top")
		(33 "B.Fab" user "Ref Des/Assembly Bottom")
	)
	(footprint ""
		(layer "F.Cu")
		(at 353.248214 -251.375418 90)
		(property "Reference" "C1018"
			(at 0 0 90)
			(layer "F.SilkS")
			(hide yes)
			(effects
				(font
					(size 1.27 1.27)
				)
			)
		)
		(property "Value" ""
			(at 0 0 90)
			(layer "F.Fab")
			(effects
				(font
					(size 1.27 1.27)
				)
			)
		)
		(duplicate_pad_numbers_are_jumpers no)
		(fp_line
			(start 0.7874 -0.4064)
			(end 0.7874 0.4064)
			(stroke
				(width 0.1524)
				(type default)
			)
			(layer "F.SilkS")
		)
		(fp_line
			(start -0.7874 -0.4064)
			(end 0.7874 -0.4064)
			(stroke
				(width 0.1524)
				(type default)
			)
			(layer "F.SilkS")
		)
		(fp_line
			(start 0.7874 0.4064)
			(end -0.7874 0.4064)
			(stroke
				(width 0.1524)
				(type default)
			)
			(layer "F.SilkS")
		)
		(fp_line
			(start -0.7874 0.4064)
			(end -0.7874 -0.4064)
			(stroke
				(width 0.1524)
				(type default)
			)
			(layer "F.SilkS")
		)
		(fp_line
			(start -0.12065 -0.305054)
			(end -0.12065 -0.2794)
			(stroke
				(width 0.1)
				(type default)
			)
			(layer "F.Fab")
		)
		(fp_line
			(start -0.67945 -0.305054)
			(end -0.12065 -0.305054)
			(stroke
				(width 0.1)
				(type default)
			)
			(layer "F.Fab")
		)
		(fp_line
			(start 0.67945 -0.3048)
			(end 0.67945 0.3048)
			(stroke
				(width 0.1)
				(type default)
			)
			(layer "F.Fab")
		)
		(fp_line
			(start 0.12065 -0.3048)
			(end 0.67945 -0.3048)
			(stroke
				(width 0.1)
				(type default)
			)
			(layer "F.Fab")
		)
		(fp_line
			(start 0.12065 -0.2794)
			(end 0.12065 -0.3048)
			(stroke
				(width 0.1)
				(type default)
			)
			(layer "F.Fab")
		)
		(fp_line
			(start -0.12065 -0.2794)
			(end 0.12065 -0.2794)
			(stroke
				(width 0.1)
				(type default)
			)
			(layer "F.Fab")
		)
		(fp_line
			(start 0.120396 0.2794)
			(end -0.12065 0.2794)
			(stroke
				(width 0.1)
				(type default)
			)
			(layer "F.Fab")
		)
		(fp_line
			(start -0.12065 0.2794)
			(end -0.12065 0.3048)
			(stroke
				(width 0.1)
				(type default)
			)
			(layer "F.Fab")
		)
		(fp_line
			(start 0.67945 0.3048)
			(end 0.120396 0.3048)
			(stroke
				(width 0.1)
				(type default)
			)
			(layer "F.Fab")
		)
		(fp_line
			(start 0.120396 0.3048)
			(end 0.120396 0.2794)
			(stroke
				(width 0.1)
				(type default)
			)
			(layer "F.Fab")
		)
		(fp_line
			(start -0.12065 0.3048)
			(end -0.67945 0.3048)
			(stroke
				(width 0.1)
				(type default)
			)
			(layer "F.Fab")
		)
		(fp_line
			(start -0.67945 0.3048)
			(end -0.67945 -0.305054)
			(stroke
				(width 0.1)
				(type default)
			)
			(layer "F.Fab")
		)
		(pad "1" smd circle
			(at -0.40005 0 90)
			(size 0 0)
			(layers "F.Cu" "F.Mask" "F.Paste")
			(net "PVCCIN_CPU0")
		)
		(pad "2" smd circle
			(at 0.40005 0 90)
			(size 0 0)
			(layers "F.Cu" "F.Mask" "F.Paste")
			(net "GND")
		)
	)
	(footprint ""
		(layer "F.Cu")
		(at 126.065026 -339.602572 90)
		(property "Reference" "PC502"
			(at 0 0 90)
			(layer "F.SilkS")
			(hide yes)
			(effects
				(font
					(size 1.27 1.27)
				)
			)
		)
		(property "Value" ""
			(at 0 0 90)
			(layer "F.Fab")
			(effects
				(font
					(size 1.27 1.27)
				)
			)
		)
		(duplicate_pad_numbers_are_jumpers no)
		(fp_line
			(start 0.7874 -0.4064)
			(end 0.7874 0.4064)
			(stroke
				(width 0.1524)
				(type default)
			)
			(layer "F.SilkS")
		)
		(fp_line
			(start -0.7874 -0.4064)
			(end 0.7874 -0.4064)
			(stroke
				(width 0.1524)
				(type default)
			)
			(layer "F.SilkS")
		)
		(fp_line
			(start 0.7874 0.4064)
			(end -0.7874 0.4064)
			(stroke
				(width 0.1524)
				(type default)
			)
			(layer "F.SilkS")
		)
		(fp_line
			(start -0.7874 0.4064)
			(end -0.7874 -0.4064)
			(stroke
				(width 0.1524)
				(type default)
			)
			(layer "F.SilkS")
		)
		(fp_line
			(start -0.12065 -0.305054)
			(end -0.12065 -0.2794)
			(stroke
				(width 0.1)
				(type default)
			)
			(layer "F.Fab")
		)
		(fp_line
			(start -0.67945 -0.305054)
			(end -0.12065 -0.305054)
			(stroke
				(width 0.1)
				(type default)
			)
			(layer "F.Fab")
		)
		(fp_line
			(start 0.67945 -0.3048)
			(end 0.67945 0.3048)
			(stroke
				(width 0.1)
				(type default)
			)
			(layer "F.Fab")
		)
		(fp_line
			(start 0.12065 -0.3048)
			(end 0.67945 -0.3048)
			(stroke
				(width 0.1)
				(type default)
			)
			(layer "F.Fab")
		)
		(fp_line
			(start 0.12065 -0.2794)
			(end 0.12065 -0.3048)
			(stroke
				(width 0.1)
				(type default)
			)
			(layer "F.Fab")
		)
		(fp_line
			(start -0.12065 -0.2794)
			(end 0.12065 -0.2794)
			(stroke
				(width 0.1)
				(type default)
			)
			(layer "F.Fab")
		)
		(fp_line
			(start 0.120396 0.2794)
			(end -0.12065 0.2794)
			(stroke
				(width 0.1)
				(type default)
			)
			(layer "F.Fab")
		)
		(fp_line
			(start -0.12065 0.2794)
			(end -0.12065 0.3048)
			(stroke
				(width 0.1)
				(type default)
			)
			(layer "F.Fab")
		)
		(fp_line
			(start 0.67945 0.3048)
			(end 0.120396 0.3048)
			(stroke
				(width 0.1)
				(type default)
			)
			(layer "F.Fab")
		)
		(fp_line
			(start 0.120396 0.3048)
			(end 0.120396 0.2794)
			(stroke
				(width 0.1)
				(type default)
			)
			(layer "F.Fab")
		)
		(fp_line
			(start -0.12065 0.3048)
			(end -0.67945 0.3048)
			(stroke
				(width 0.1)
				(type default)
			)
			(layer "F.Fab")
		)
		(fp_line
			(start -0.67945 0.3048)
			(end -0.67945 -0.305054)
			(stroke
				(width 0.1)
				(type default)
			)
			(layer "F.Fab")
		)
		(pad "1" smd circle
			(at -0.40005 0 90)
			(size 0 0)
			(layers "F.Cu" "F.Mask" "F.Paste")
			(net "PVCCIN_CPU1_VDD5")
		)
		(pad "2" smd circle
			(at 0.40005 0 90)
			(size 0 0)
			(layers "F.Cu" "F.Mask" "F.Paste")
			(net "GND")
		)
	)
	(footprint ""
		(layer "F.Cu")
		(at 95.249238 -408.517344 -90)
		(property "Reference" "C678"
			(at 0 0 270)
			(layer "F.SilkS")
			(hide yes)
			(effects
				(font
					(size 1.27 1.27)
				)
			)
		)
		(property "Value" ""
			(at 0 0 270)
			(layer "F.Fab")
			(effects
				(font
					(size 1.27 1.27)
				)
			)
		)
		(duplicate_pad_numbers_are_jumpers no)
		(fp_line
			(start -0.299974 0.150114)
			(end -0.299974 -0.150114)
			(stroke
				(width 0.1)
				(type default)
			)
			(layer "F.Fab")
		)
		(fp_line
			(start 0.299974 0.150114)
			(end -0.299974 0.150114)
			(stroke
				(width 0.1)
				(type default)
			)
			(layer "F.Fab")
		)
		(fp_line
			(start -0.299974 -0.150114)
			(end 0.299974 -0.150114)
			(stroke
				(width 0.1)
				(type default)
			)
			(layer "F.Fab")
		)
		(fp_line
			(start 0.299974 -0.150114)
			(end 0.299974 0.150114)
			(stroke
				(width 0.1)
				(type default)
			)
			(layer "F.Fab")
		)
		(pad "1" smd rect
			(at -0.2667 0 270)
			(size 0.3048 0.381)
			(layers "F.Cu" "F.Mask" "F.Paste")
			(net "P5E_CPU1_PE4_TX_C_DN<15>")
		)
		(pad "2" smd rect
			(at 0.2667 0 270)
			(size 0.3048 0.381)
			(layers "F.Cu" "F.Mask" "F.Paste")
			(net "P5E_CPU1_PE4_TX_DN<15>")
		)
	)
)
